# SCM (Grand Teton) — schematic parts with pin connectivity, parts 387–517 of 1428; source: Cadence DE-HDL packaged netlist (pstxprt.dat, pstxnet.dat, pstchip.dat)

J40  SCONN16_ACASPI006P06  SCONN16_ACA-SPI-006-P06 IO  pkg SOCKET16SXA  page 45
  1  HOLD_N  BI  = SPI_PCH_IO3_FLASH_R1
  2  VCC  POWER  = P3V3_AUX
  3  NC0  BI  = RST_SPI_PCH_FLASH_R1_N
  4  NC1  BI  = TP_J40_4
  5  NC2  BI  = TP_J40_5
  6  NC3  BI  = TP_J40_6
  7  CS_N  BI  = SPI_PCH_CS0_FLASH_R1_N
  8  DO  BI  = SPI_PCH_IO1_FLASH_R1
  9  WP_N  BI  = SPI_PCH_IO2_FLASH_R1
  10  GND  POWER  = GND
  11  NC4  BI  = TP_J40_11
  12  NC6  BI  = TP_J40_12
  13  NC7  BI  = TP_J40_13
  14  NC8  BI  = TP_J40_14
  15  DI  BI  = SPI_PCH_IO0_FLASH_R1
  16  CLK  BI  = SPI_PCH_CLK_FLASH_R1

L2  Q_INDUCTOR  BLM18PG121SN1D/2000MA IND  pkg SMLF  page 17 : 1 = P1V2_AUX ; 2 = P3V3_STBY_PLLAHVDD
L3  Q_INDUCTOR  BLM18PG121SN1D/2000MA IND  pkg SMLF  page 15 : 1 = P1V8_AUX ; 2 = P1V8_BMC_USB2AV18
L4  Q_INDUCTOR  BLM18PG121SN1D/2000MA IND  pkg SMLF  page 15 : 1 = P3V3_AUX ; 2 = P3V3_BMC_USB2AV33
L5  Q_INDUCTOR  BLM18PG121SN1D/2000MA IND  pkg SMLF  page 17 : 1 = P1V8_AUX ; 2 = P1V8_STBY_AVDDPLL
L6  Q_INDUCTOR  BLM18PG121SN1D/2000MA IND  pkg SMLF  page 17 : 1 = P1V0_AUX ; 2 = P1V0_STBY_RC_VCC10A
L7  Q_INDUCTOR  BLM18PG121SN1D/2000MA IND  pkg SMLF  page 17 : 1 = P3V3_AUX ; 2 = P3V3_STBY_DACAV33
L8  Q_INDUCTOR  BLM18PG121SN1D/2000MA IND  pkg SMLF  page 16 : 1 = P1V0_AUX ; 2 = P1V0_STBY_PLAVDD
L9  Q_INDUCTOR  BLM18PG121SN1D/2000MA EMPTY  pkg SMLF  page 17 : 1 = P3V3_AUX ; 2 = P3V3_STBY_PLLAHVDD
L10  Q_INDUCTOR  BLM18PG121SN1D/2000MA IND  pkg SMLF  page 16 : 1 = P1V8_AUX ; 2 = P1V8_STBY_PE_VCC18A
L11  Q_INDUCTOR  BLM18PG121SN1D/2000MA IND  pkg SMLF  page 16 : 1 = P1V2_AUX ; 2 = P1V2_STBY_MVDD_CK
L12  Q_INDUCTOR  BLM18PG121SN1D/2000MA IND  pkg SMLF  page 16 : 1 = P3V3_AUX ; 2 = A_BMC_ADCAV33
L13  Q_INDUCTOR  BLM18PG121SN1D/2000MA IND  pkg SMLF  page 17 : 1 = P1V0_AUX ; 2 = P1V0_STBY_PE_VCC10A
L14  Q_INDUCTOR  BLM18PG121SN1D/2000MA IND  pkg SMLF  page 17 : 1 = P1V8_AUX ; 2 = P1V8_STBY_RC_VCC18A
L15  Q_INDUCTOR  BLM18PG121SN1D/2000MA IND  pkg SMLF  page 17 : 1 = P1V0_AUX ; 2 = P1V0_STBY_DP_VCC10A
L16  Q_INDUCTOR  BLM18PG121SN1D/2000MA IND  pkg SMLF  page 17 : 1 = P1V8_AUX ; 2 = P1V8_STBY_DP_VCC18A
L17  Q_INDUCTOR  BLM18EG121SN1D/2A IND  pkg SMLF  page 17 : 1 = PGPPA_BMC_AUX_L ; 2 = PGPPA_BMC_AUX
L19  Q_INDUCTOR  BLM18EG121SN1D/2A IND  pkg SMLF  page 41 : 1 = P3V3_AUX ; 2 = PVCCA_AUX_PLD

L21  Q_INDUCTOR4P_12  67/320MA EMPTY  pkg L_DLW21HNXA  page 29
  1  \1\  BI  = USB3_01_MUX_FB_TXP
  2  \2\  BI  = USB3_01_FB_TXP
  3  \3\  BI  = USB3_01_FB_TXN
  4  \4\  BI  = USB3_01_MUX_FB_TXN

L22  Q_INDUCTOR4P_12  67/320MA EMPTY  pkg L_DLW21HNXA  page 29
  1  \1\  BI  = USB3_01_MUX_FB_RXP
  2  \2\  BI  = USB3_01_FB_RXP
  3  \3\  BI  = USB3_01_FB_RXN
  4  \4\  BI  = USB3_01_MUX_FB_RXN

L23  Q_INDUCTOR4P_12  67/320MA EMPTY  pkg L_DLW21HNXA  page 29
  1  \1\  BI  = USB_FPNL_DP
  2  \2\  BI  = USB2_01_F_DP
  3  \3\  BI  = USB2_01_F_DN
  4  \4\  BI  = USB_FPNL_DN

L28  Q_INDUCTOR  BLM18BB470/500MA IND  pkg SMLF  page 23 : 1 = V_DACB ; 2 = V_DACB_IO
L29  Q_INDUCTOR  BLM18BB470/500MA IND  pkg SMLF  page 23 : 1 = V_DACG ; 2 = V_DACG_IO
L30  Q_INDUCTOR  BLM18BB470/500MA IND  pkg SMLF  page 23 : 1 = V_DACR ; 2 = V_DACR_IO
ME1  ME_DUMMY_SYMBOL  QUANTA_LOGO_7X26 EMPTY  pkg QUANTA_LOGO_7X26  page 59
ME2  ME_DUMMY_SYMBOL  WEEE EMPTY  pkg WEEE  page 59
ME4  ME_DUMMY_SYMBOL  SNLABEL_7X7 EMPTY  pkg SNLABEL_7X7  page 59

OSC1  OSC4_7X25000018  25MHZ MISC  pkg X_7X  page 15
  1  OE  IN  = PU_25M_BMC_CLK_EN
  2  GND  POWER  = GND
  3  \out\  OUT  = BMC_CLK_25M_R
  4  VDD  POWER  = P3V3_RGM

OSC2  OSC4_7X25000018  25MHZ MISC  pkg X_7X  page 34
  1  OE  IN  = PU_25M_FPGA_CLK_EN
  2  GND  POWER  = GND
  3  \out\  OUT  = CLK_25M_OSC_FPGA_R
  4  VDD  POWER  = P3V3_AUX

PC205  Q_CAP  0.1UF 25V 10% X7R  pkg 0402  page 51 : 1 = EN_P5V_AUX ; 2 = GND
PC206  Q_CAP  22UF 16V 20% X6S  pkg C0805  page 51 : 1 = SW_P5V_AUX_FLT ; 2 = GND
PC207  Q_CAP  22UF 16V 20% X6S  pkg C0805  page 51 : 1 = SW_P5V_AUX_FLT ; 2 = GND
PC208  Q_CAP  1UF 25V 10% X6S  pkg C0402  page 51 : 1 = P5V_AUX_VCC ; 2 = GND
PC210  Q_CAP  0.1UF 25V 10% X7R  pkg 0402  page 51 : 1 = SW_P5V_AUX_FLT ; 2 = GND
PC212  Q_CAP  0.1UF 25V 10% X7R  pkg 0402  page 51 : 1 = P5V_AUX ; 2 = GND
PC213  Q_CAP  22UF 10V 20% X6S  pkg C0805  page 51 : 1 = P5V_AUX ; 2 = GND
PC214  Q_CAP  22UF 10V 20% X6S  pkg C0805  page 51 : 1 = P5V_AUX ; 2 = GND
PC215  Q_CAP  22UF 10V 20% X6S  pkg C0805  page 51 : 1 = P5V_AUX ; 2 = GND
PC216  Q_CAP  0.22UF 16V 10% X7R  pkg 0402  page 51 : 1 = SW_P5V_AUX_BST ; 2 = SW_P5V_AUX_SW
PC217  Q_CAP  22UF 10V 20% X6S  pkg C0805  page 51 : 1 = P5V_AUX ; 2 = GND
PC218  Q_CAP  22UF 16V 20% X6S  pkg C0805  page 52 : 1 = SW_P3V3_AUX_FLT ; 2 = GND
PC219  Q_CAP  22UF 16V 20% X6S  pkg C0805  page 52 : 1 = SW_P3V3_AUX_FLT ; 2 = GND
PC221  Q_CAP  1UF 25V 10% X6S  pkg C0402  page 52 : 1 = P3V3_AUX_VCC ; 2 = GND
PC223  Q_CAP  0.1UF 25V 10% X7R  pkg 0402  page 52 : 1 = SW_P3V3_AUX_FLT ; 2 = GND
PC224  Q_CAP  0.22UF 16V 10% X7R  pkg 0402  page 52 : 1 = SW_P3V3_AUX_BST ; 2 = SW_P3V3_AUX_SW
PC225  Q_CAP  0.1UF 25V 10% X7R  pkg 0402  page 52 : 1 = P3V3_AUX ; 2 = GND
PC226  Q_CAP  22UF 10V 20% X6S  pkg C0805  page 52 : 1 = P3V3_AUX ; 2 = GND
PC227  Q_CAP  22UF 10V 20% X6S  pkg C0805  page 52 : 1 = P3V3_AUX ; 2 = GND
PC228  Q_CAP  22UF 10V 20% X6S  pkg C0805  page 52 : 1 = P3V3_AUX ; 2 = GND
PC229  Q_CAP  22UF 10V 20% X6S  pkg C0805  page 52 : 1 = P3V3_AUX ; 2 = GND
PC239  Q_CAP  100PF 50V 5% NPO  pkg 0402  page 52 : 1 = P3V3_AUX_FB_RC ; 2 = P3V3_AUX
PC250  Q_CAP  1UF 25V 10% X6S  pkg C0402  page 55 : 1 = P1V2_AUX_VCC ; 2 = GND
PC251  Q_CAP  10UF 25V 10% X6S  pkg C0805  page 55 : 1 = SW_P1V2_AUX_FLT ; 2 = GND
PC252  Q_CAP  10UF 25V 10% X6S  pkg C0805  page 55 : 1 = SW_P1V2_AUX_FLT ; 2 = GND
PC253  Q_CAP  0.1UF 25V 10% X7R  pkg 0402  page 55 : 1 = SW_P1V2_AUX_FLT ; 2 = GND
PC254  Q_CAP  0.22UF 16V 10% X7R  pkg 0402  page 55 : 1 = SW_P1V2_AUX_BST ; 2 = SW_P1V2_AUX_SW
PC255  Q_CAP  0.1UF 25V 10% X7R  pkg 0402  page 55 : 1 = P1V2_AUX ; 2 = GND
PC256  Q_CAP  22UF 4V 20% X6S  pkg 0805  page 55 : 1 = P1V2_AUX ; 2 = GND
PC257  Q_CAP  22UF 4V 20% X6S  pkg 0805  page 55 : 1 = P1V2_AUX ; 2 = GND
PC258  Q_CAP  22UF 4V 20% X6S  pkg 0805  page 55 : 1 = P1V2_AUX ; 2 = GND
PC259  Q_CAP  22UF 4V 20% X6S  pkg 0805  page 55 : 1 = P1V2_AUX ; 2 = GND
PC260  Q_CAP  1UF 25V 10% X6S  pkg C0402  page 56 : 1 = P1V0_AUX_VCC ; 2 = GND
PC261  Q_CAP  10UF 25V 10% X6S  pkg C0805  page 56 : 1 = SW_P1V0_AUX_FLT ; 2 = GND
PC262  Q_CAP  10UF 25V 10% X6S  pkg C0805  page 56 : 1 = SW_P1V0_AUX_FLT ; 2 = GND
PC263  Q_CAP  0.1UF 25V 10% X7R  pkg 0402  page 56 : 1 = SW_P1V0_AUX_FLT ; 2 = GND
PC264  Q_CAP  0.22UF 16V 10% X7R  pkg 0402  page 56 : 1 = SW_P1V0_AUX_BST ; 2 = SW_P1V0_AUX_SW
PC266  Q_CAP  0.1UF 25V 10% X7R  pkg 0402  page 56 : 1 = P1V0_AUX ; 2 = GND
PC267  Q_CAP  22UF 4V 20% X6S  pkg 0805  page 56 : 1 = P1V0_AUX ; 2 = GND
PC268  Q_CAP  22UF 4V 20% X6S  pkg 0805  page 56 : 1 = P1V0_AUX ; 2 = GND
PC269  Q_CAP  22UF 4V 20% X6S  pkg 0805  page 56 : 1 = P1V0_AUX ; 2 = GND
PC270  Q_CAP  22UF 4V 20% X6S  pkg 0805  page 56 : 1 = P1V0_AUX ; 2 = GND
PC271  Q_CAP  0.1UF 25V 10% X7R  pkg 0402  page 51 : 1 = P5V_AUX_REF ; 2 = GND
PC272  Q_CAP  68PF 50V 5% COG  pkg C0402  page 51 : 1 = P5V_AUX_FB ; 2 = P5V_AUX
PC273  Q_CAP  3300PF 50V 10% X7R  pkg 0402  page 52 : 1 = P3V3_AUX_REF ; 2 = GND
PL4  Q_INDUCTOR  BLM18SN220TN1D/8000MA IND  pkg SMLF  page 51 : 1 = P12V_AUX ; 2 = SW_P5V_AUX_FLT
PL19  Q_INDUCTOR  BLM18SN220TN1D/8000MA IND  pkg SMLF  page 52 : 1 = P12V_AUX ; 2 = SW_P3V3_AUX_FLT
PL29  Q_INDUCTOR  BLM18SN220TN1D/8000MA IND  pkg SMLF  page 55 : 1 = P12V_AUX ; 2 = SW_P1V2_AUX_FLT
PL31  Q_INDUCTOR  1UH IND  pkg SMLF  page 55 : 1 = SW_P1V2_AUX_SW ; 2 = P1V2_AUX
PL32  Q_INDUCTOR  BLM18SN220TN1D/8000MA IND  pkg SMLF  page 56 : 1 = P12V_AUX ; 2 = SW_P1V0_AUX_FLT
PL33  Q_INDUCTOR  1UH IND  pkg SMLF  page 56 : 1 = SW_P1V0_AUX_SW ; 2 = P1V0_AUX
PL34  Q_INDUCTOR  4.7UH IND  pkg SMLF  page 51 : 1 = SW_P5V_AUX_SW ; 2 = P5V_AUX
PL35  Q_INDUCTOR  3.3UH/6A IND  pkg SMLF  page 52 : 1 = SW_P3V3_AUX_SW ; 2 = P3V3_AUX
PR193  Q_RES  0 5% CHIP  pkg 0402LF  page 56 : 1 = P3V3_AUX ; 2 = PVCC2_AUX
PR205  Q_RES  0 5% EMPTY  pkg 0402LF  page 56 : 1 = P5V_AUX ; 2 = PVCC2_AUX
PR241  Q_RES  10K 1% CHIP  pkg 0402LF  page 51 : 1 = P5V_AUX_VCC ; 2 = PWRGD_P5V_AUX_R
PR242  Q_RES  10K 1% CHIP  pkg 0402LF  page 52 : 1 = P3V3_AUX ; 2 = PWRGD_P3V3_AUX_R
PR245  Q_RES  100K 1% EMPTY  pkg 0402LF  page 51 : 1 = PWRGD_P5V_AUX_R ; 2 = GND
PR274  Q_RES  0 5% CHIP  pkg 0402LF  page 55 : 1 = P3V3_AUX ; 2 = PVCC1_AUX
PR275  Q_RES  0 5% EMPTY  pkg 0402LF  page 55 : 1 = P5V_AUX ; 2 = PVCC1_AUX
PR276  Q_RES  5.49K 1% CHIP  pkg 0402LF  page 52 : 1 = GND ; 2 = P3V3_AUX_CS
PR496  Q_RES  150K 1% CHIP  pkg 0402LF  page 55 : 1 = P1V2_AUX_MODE ; 2 = GND
PR498  Q_RES  10K 1% CHIP  pkg 0402LF  page 55 : 1 = P3V3_AUX ; 2 = PWRGD_P1V2_AUX_R
PR500  Q_RES  10K 1% CHIP  pkg 0402LF  page 56 : 1 = P3V3_AUX ; 2 = PWRGD_P1V0_AUX_R
PR521  Q_RES  681K 1% CHIP  pkg 0402LF  page 51 : 1 = P12V_AUX ; 2 = EN_P5V_AUX
PR522  Q_RES  100K 1% CHIP  pkg 0402LF  page 51 : 1 = EN_P5V_AUX ; 2 = GND
PR525  Q_RES  20.5K 1% CHIP  pkg 0402LF  page 51 : 1 = P5V_AUX_CS ; 2 = GND
PR526  Q_RES  12.4K 1% CHIP  pkg 0402LF  page 51 : 1 = P5V_AUX_FB ; 2 = GND
PR527  Q_RES  91K 1% CHIP  pkg 0402LF  page 51 : 1 = P5V_AUX_FB ; 2 = P5V_AUX
PR530  Q_RES  12.4K 1% CHIP  pkg 0402LF  page 52 : 1 = GND ; 2 = P3V3_AUX_FB_RC
PR532  Q_RES  60.4K 1% CHIP  pkg 0402LF  page 52 : 1 = GND ; 2 = P3V3_AUX_MODE
PR534  Q_RES  56K 1% CHIP  pkg 0402LF  page 52 : 1 = P3V3_AUX_FB_RC ; 2 = P3V3_AUX
PR539  Q_RES  5.1 5% CHIP  pkg 0402LF  page 55 : 1 = PVCC1_AUX ; 2 = P1V2_AUX_VCC
PR541  Q_RES  5.1 5% CHIP  pkg 0402LF  page 56 : 1 = PVCC2_AUX ; 2 = P1V0_AUX_VCC
PR543  Q_RES  100K 1% CHIP  pkg 0402LF  page 56 : 1 = P1V0_AUX_MODE ; 2 = GND

PU1  MPQ8626GDZ  MPQ8626GD-Z IC  pkg QFN14_0-5_3X2XA  page 52
  1  PGND1  POWER  = GND
  2  SW1  OUT  = SW_P3V3_AUX_SW
  3  VIN  IN  = SW_P3V3_AUX_FLT
  4  CS  IN  = P3V3_AUX_CS
  5  EN  IN  = PWRGD_EN_P3V3_R
  6  FB  IN  = P3V3_AUX_FB_RC
  7  AGND  POWER  = GND
  8  TRK_REF  IN  = P3V3_AUX_REF
  9  PGOOD  OUT  = PWRGD_P3V3_AUX_R
  10  BST  IN  = SW_P3V3_AUX_BST_R
  11  SW2  OUT  = SW_P3V3_AUX_SW
  12  MODE  IN  = P3V3_AUX_MODE
  13  VCC  OUT  = P3V3_AUX_VCC
  14  PGND2  POWER  = GND

PU38  MPQ8633AGLEC807Z  MPQ8633AGLE-C807-Z IC  pkg QFN14_4X3  page 51
  1  BST  IN  = SW_P5V_AUX_BST
  2  AGND  POWER  = GND
  3  CS  IN  = P5V_AUX_CS
  4  MODE  IN  = GND
  5  TRK_REF  IN  = P5V_AUX_REF
  6  RGND  POWER  = GND
  7  FB  IN  = P5V_AUX_FB
  8  EN  IN  = EN_P5V_AUX
  9  PGOOD  OUT  = PWRGD_P5V_AUX_R
  10  VIN1  IN  = SW_P5V_AUX_FLT
  11_18  PGND  POWER  = GND
  19  VCC  POWER  = P5V_AUX_VCC
  20  SW  OUT  = SW_P5V_AUX_SW
  21  VIN2  IN  = SW_P5V_AUX_FLT

PU41  NB695GDZ  NB695GD-Z IC  pkg QFN13_2X3  page 55
  1  VIN  POWER  = SW_P1V2_AUX_FLT
  2  PGND  POWER  = GND
  3  C1  IN  = GND
  4  C0  IN  = GND
  5  EN  IN  = EN_P1V2_AUX_R
  6  \lp#\  IN  = P1V2_AUX_VCC
  7  MODE  IN  = P1V2_AUX_MODE
  8  SW  POWER  = SW_P1V2_AUX_SW
  9  BST  POWER  = SW_P1V2_AUX_BST
  10  \3v3\  POWER  = P1V2_AUX_VCC
  11  AGND  POWER  = GND
  12  VOUT  POWER  = P1V2_AUX
  13  PG  OUT  = PWRGD_P1V2_AUX_R

PU42  NB695GDZ  NB695GD-Z IC  pkg QFN13_2X3  page 56
  1  VIN  POWER  = SW_P1V0_AUX_FLT
  2  PGND  POWER  = GND
  3  C1  IN  = P1V0_AUX_VCC
  4  C0  IN  = GND
  5  EN  IN  = EN_P1V0_AUX_R
  6  \lp#\  IN  = P1V0_AUX_VCC
  7  MODE  IN  = P1V0_AUX_MODE
  8  SW  POWER  = SW_P1V0_AUX_SW
  9  BST  POWER  = SW_P1V0_AUX_BST
  10  \3v3\  POWER  = P1V0_AUX_VCC
  11  AGND  POWER  = GND
  12  VOUT  POWER  = P1V0_AUX
  13  PG  OUT  = PWRGD_P1V0_AUX_R

Q1  MMBT39047F  MMBT3904-7-F IC  pkg SOT23_BEC  page 22
  B  \1\  IN  = BJT_Q3_C
  C  \3\  BI  = RST_BMC_EXTRST_R2_N
  E  \2\  BI  = GND

Q2  MOSFET_NCH_DUAL  2N7002KDW IC  pkg SOT363XD  page 23
  1  S1  BI  = V_BMC_DDC_SDA
  2  G1  BI  = V_BMC_DDC_LS_GATE
  3  D2  BI  = V_BMC_LS_DDC_SCL
  4  S2  BI  = V_BMC_DDC_SCL
  5  G2  BI  = V_BMC_DDC_LS_GATE
  6  D1  BI  = V_BMC_LS_DDC_SDA

Q3  MMBT39047F  MMBT3904-7-F IC  pkg SOT23_BEC  page 22
  B  \1\  IN  = BJT_Q3_B
  C  \3\  BI  = BJT_Q3_C
  E  \2\  BI  = GND

Q4  MOSFET_PCH_GDS  NTR1P02LT1G EMPTY  pkg SOT23_GDS_2-9X1-3XC  page 17
  D  D  BI  = PGPPA_BMC_AUX_L
  G  G  IN  = LPC_ESPI_SEL_N
  S  S  BI  = P3V3_AUX

Q5  MOSFET_NCH_4D1S  NTGS4141NT1G IC  pkg TSOP6XB  page 17
  1  \1\  BI  = PGPPA_BMC_AUX_L
  2  \2\  BI  = PGPPA_BMC_AUX_L
  3  \3\  IN  = LPC_ESPI_SEL_N
  4  \4\  BI  = P1V8_AUX
  5  \5\  BI  = PGPPA_BMC_AUX_L
  6  \6\  BI  = PGPPA_BMC_AUX_L

Q6  2N7002A7  2N7002A-7 IC  pkg SOT23_GDSXC  page 29
  D  D  BI  = FM_DEBUG_PORT_R_PRSNT_N
  G  G  IN  = DEBUG_PORT_PRSNT
  S  S  BI  = GND

Q7  2N7002A7  2N7002A-7 IC  pkg SOT23_GDSXC  page 27
  D  D  BI  = Q7_D
  G  G  IN  = LPC_ESPI_SEL_R1
  S  S  BI  = SPI_BMC_TPM_MOSI

Q8  2N7002A7  2N7002A-7 IC  pkg SOT23_GDSXC  page 28
  D  D  BI  = FM_SOL_UART_CH_SEL_R3
  G  G  IN  = FM_UART_SEL_N
  S  S  BI  = GND

Q9  MOSFET_NCH_DUAL  PJT138K IC  pkg SOT363XD  page 49
  1  S1  BI  = GND
  2  G1  BI  = ID_LED_BUF
  6  D1  BI  = ID_LED_D_P3V3_AUX

Q10  MOSFET_N_GSD  DMG6968U-7 IC  pkg SOT23_GDSXC  page 17
  D  DRAIN  BI  = LPC_ESPI_SEL_N
  G  GATE  IN  = LPC_ESPI_SEL_R
  S  SOURCE  BI  = GND

Q11  MOSFET_N_GSD  NX7002AK IC  pkg SOT23_GDSXE  page 15
  D  DRAIN  BI  = P3V_BAT_R1
  G  GATE  IN  = BATTERY_DETECT_R
  S  SOURCE  BI  = P3V_BAT_SENSOR

Q12  MOSFET_DUAL_6P  2N7002KDW IC  pkg SOT363XD  page 49
  1  S1  BI  = GND
  2  G1  BI  = PWR_LED
  3  D2  BI  = HDD_LED_BUF
  4  S2  BI  = GND
  5  G2  BI  = HDD_LED_N
  6  D1  BI  = PWR_LED_BUF_N

Q13  MOSFET_NCH_DUAL  PJT138K IC  pkg SOT363XD  page 50
  1  S1  BI  = GND
  2  G1  BI  = PWRGD_P1V0_AUX_DELAY
  6  D1  BI  = LED_D22_R1

R1  Q_RES  0 5% EMPTY  pkg 0402LF  page 20 : 1 = M_BMC_DDR4_BG1 ; 2 = M_BMC_DDR4_MBG1
R2  Q_RES  0 5% CHIP  pkg 0402LF  page 20 : 1 = M_BMC_DDR4_BG1 ; 2 = GND
R3  Q_RES  0 5% CHIP  pkg 0402LF  page 20 : 1 = M_BMC_DDR4_ZQU ; 2 = GND
R4  Q_RES  1K 1% CHIP  pkg 0402LF  page 20 : 1 = PD_M_BMC_DDR4_PAR ; 2 = GND
R5  Q_RES  1K 1% CHIP  pkg 0402LF  page 20 : 1 = PD_M_BMC_DDR4_TEN ; 2 = GND
R6  Q_RES  240 1% CHIP  pkg 0402LF  page 20 : 1 = PD_M_BMC_DDR4_ZQ ; 2 = GND
R7  Q_RES  60.4 1% CHIP  pkg 0402LF  page 20 : 1 = M_BMC_DDR4_MCLK_DN ; 2 = M_BMC_DDR4_MCLK_C
R8  Q_RES  60.4 1% CHIP  pkg 0402LF  page 20 : 1 = M_BMC_DDR4_MCLK_DP ; 2 = M_BMC_DDR4_MCLK_C
R9  Q_RES  4.7K 1% CHIP  pkg 0402LF  page 20 : 1 = M_BMC_DDR4_ALERT_N ; 2 = P1V2_AUX
R10  Q_RES  0 5% CHIP  pkg 0402LF  page 34 : 1 = RST_SRST_PLD_BMC_R2_N ; 2 = RST_SRST_PLD_BMC_R_N
